# T6G (Grand Teton) — schematic netlist excerpt (pin names and nets, part order shuffled) for the footprints in the layout excerpt that follows; sources: Cadence DE-HDL packaged netlist, KiCad conversion of 04192023_DAF0TMB3IC0_F0TG_MB_C_brd_V02_OCP.brd

PR3798  Q_RES  10 1% CHIP  pkg 0402LF  page 134 : A = P3V3_AUX ; B = P3V3_OCP_VCC_1
PR295  Q_RES  49.9 1% CHIP  pkg 0402LF  page 193 : A = VSENSE_VSS_SENSE_A_P0 ; B = GND

(kicad_pcb
	(version 20260206)
	(generator "pcbnew")
	(generator_version "10.0")
	(general
		(thickness 1.6)
		(legacy_teardrops no)
	)
	(paper "A4")
	(title_block
		(title "04192023_DAF0TMB3IC0_F0TG_MB_C_brd_V02_OCP.brd")
		(comment 1 "Grand Teton / footprints 3559-3560 of 8354")
	)
	(layers
		(0 "F.Cu" signal "TOP")
		(4 "In1.Cu" signal "GND")
		(6 "In2.Cu" signal "IN1")
		(8 "In3.Cu" signal "GND1")
		(10 "In4.Cu" signal "IN2")
		(12 "In5.Cu" signal "GND2")
		(14 "In6.Cu" signal "IN3")
		(16 "In7.Cu" signal "GND3")
		(18 "In8.Cu" signal "VCC")
		(20 "In9.Cu" signal "VCC1")
		(22 "In10.Cu" signal "GND4")
		(24 "In11.Cu" signal "IN4")
		(26 "In12.Cu" signal "GND5")
		(28 "In13.Cu" signal "IN5")
		(30 "In14.Cu" signal "GND6")
		(32 "In15.Cu" signal "IN6")
		(34 "In16.Cu" signal "GND7")
		(2 "B.Cu" signal "BOTTOM")
		(9 "F.Adhes" user "F.Adhesive")
		(11 "B.Adhes" user "B.Adhesive")
		(13 "F.Paste" user "Package Geometry/Pastemask Top")
		(15 "B.Paste" user "Package Geometry/Pastemask Bottom")
		(5 "F.SilkS" user "Ref Des/Silkscreen Top")
		(7 "B.SilkS" user "Ref Des/Silkscreen Bottom")
		(1 "F.Mask" user "Board Geometry/Soldermask Top")
		(3 "B.Mask" user "Board Geometry/Soldermask Bottom")
		(17 "Dwgs.User" user "User.Drawings")
		(19 "Cmts.User" user "User.Comments")
		(21 "Eco1.User" user "User.Eco1")
		(23 "Eco2.User" user "User.Eco2")
		(25 "Edge.Cuts" user "Board Geometry/Outline")
		(27 "Margin" user)
		(31 "F.CrtYd" user "Package Geometry/Place Bound Top")
		(29 "B.CrtYd" user "Package Geometry/Place Bound Bottom")
		(35 "F.Fab" user "Ref Des/Assembly Top")
		(33 "B.Fab" user "Ref Des/Assembly Bottom")
	)
	(footprint ""
		(layer "F.Cu")
		(at 435.997858 -106.76636 180)
		(property "Reference" "PR3798"
			(at 0 0 180)
			(layer "F.SilkS")
			(hide yes)
			(effects
				(font
					(size 1.27 1.27)
				)
			)
		)
		(property "Value" ""
			(at 0 0 180)
			(layer "F.Fab")
			(effects
				(font
					(size 1.27 1.27)
				)
			)
		)
		(duplicate_pad_numbers_are_jumpers no)
		(fp_line
			(start 0.7874 0.4064)
			(end -0.7874 0.4064)
			(stroke
				(width 0.1524)
				(type default)
			)
			(layer "F.SilkS")
		)
		(fp_line
			(start 0.7874 -0.4064)
			(end 0.7874 0.4064)
			(stroke
				(width 0.1524)
				(type default)
			)
			(layer "F.SilkS")
		)
		(fp_line
			(start -0.7874 0.4064)
			(end -0.7874 -0.4064)
			(stroke
				(width 0.1524)
				(type default)
			)
			(layer "F.SilkS")
		)
		(fp_line
			(start -0.7874 -0.4064)
			(end 0.7874 -0.4064)
			(stroke
				(width 0.1524)
				(type default)
			)
			(layer "F.SilkS")
		)
		(fp_line
			(start 0.67945 0.3048)
			(end 0.120396 0.3048)
			(stroke
				(width 0.1)
				(type default)
			)
			(layer "F.Fab")
		)
		(fp_line
			(start 0.67945 -0.3048)
			(end 0.67945 0.3048)
			(stroke
				(width 0.1)
				(type default)
			)
			(layer "F.Fab")
		)
		(fp_line
			(start 0.12065 -0.2794)
			(end 0.12065 -0.3048)
			(stroke
				(width 0.1)
				(type default)
			)
			(layer "F.Fab")
		)
		(fp_line
			(start 0.12065 -0.3048)
			(end 0.67945 -0.3048)
			(stroke
				(width 0.1)
				(type default)
			)
			(layer "F.Fab")
		)
		(fp_line
			(start 0.120396 0.3048)
			(end 0.120396 0.2794)
			(stroke
				(width 0.1)
				(type default)
			)
			(layer "F.Fab")
		)
		(fp_line
			(start 0.120396 0.2794)
			(end -0.12065 0.2794)
			(stroke
				(width 0.1)
				(type default)
			)
			(layer "F.Fab")
		)
		(fp_line
			(start -0.12065 0.3048)
			(end -0.67945 0.3048)
			(stroke
				(width 0.1)
				(type default)
			)
			(layer "F.Fab")
		)
		(fp_line
			(start -0.12065 0.2794)
			(end -0.12065 0.3048)
			(stroke
				(width 0.1)
				(type default)
			)
			(layer "F.Fab")
		)
		(fp_line
			(start -0.12065 -0.2794)
			(end 0.12065 -0.2794)
			(stroke
				(width 0.1)
				(type default)
			)
			(layer "F.Fab")
		)
		(fp_line
			(start -0.12065 -0.305054)
			(end -0.12065 -0.2794)
			(stroke
				(width 0.1)
				(type default)
			)
			(layer "F.Fab")
		)
		(fp_line
			(start -0.67945 0.3048)
			(end -0.67945 -0.305054)
			(stroke
				(width 0.1)
				(type default)
			)
			(layer "F.Fab")
		)
		(fp_line
			(start -0.67945 -0.305054)
			(end -0.12065 -0.305054)
			(stroke
				(width 0.1)
				(type default)
			)
			(layer "F.Fab")
		)
		(pad "1" smd circle
			(at -0.40005 0 180)
			(size 0 0)
			(layers "F.Cu" "F.Mask" "F.Paste")
			(net "P3V3_AUX")
		)
		(pad "2" smd circle
			(at 0.40005 0 180)
			(size 0 0)
			(layers "F.Cu" "F.Mask" "F.Paste")
			(net "P3V3_OCP_VCC_1")
		)
	)
	(footprint ""
		(layer "F.Cu")
		(at 341.56904 -171.308522)
		(property "Reference" "PR295"
			(at 0 0 0)
			(layer "F.SilkS")
			(hide yes)
			(effects
				(font
					(size 1.27 1.27)
				)
			)
		)
		(property "Value" ""
			(at 0 0 0)
			(layer "F.Fab")
			(effects
				(font
					(size 1.27 1.27)
				)
			)
		)
		(duplicate_pad_numbers_are_jumpers no)
		(fp_line
			(start -0.7874 -0.4064)
			(end 0.7874 -0.4064)
			(stroke
				(width 0.1524)
				(type default)
			)
			(layer "F.SilkS")
		)
		(fp_line
			(start -0.7874 0.4064)
			(end -0.7874 -0.4064)
			(stroke
				(width 0.1524)
				(type default)
			)
			(layer "F.SilkS")
		)
		(fp_line
			(start 0.7874 -0.4064)
			(end 0.7874 0.4064)
			(stroke
				(width 0.1524)
				(type default)
			)
			(layer "F.SilkS")
		)
		(fp_line
			(start 0.7874 0.4064)
			(end -0.7874 0.4064)
			(stroke
				(width 0.1524)
				(type default)
			)
			(layer "F.SilkS")
		)
		(fp_line
			(start -0.67945 -0.305054)
			(end -0.12065 -0.305054)
			(stroke
				(width 0.1)
				(type default)
			)
			(layer "F.Fab")
		)
		(fp_line
			(start -0.67945 0.3048)
			(end -0.67945 -0.305054)
			(stroke
				(width 0.1)
				(type default)
			)
			(layer "F.Fab")
		)
		(fp_line
			(start -0.12065 -0.305054)
			(end -0.12065 -0.2794)
			(stroke
				(width 0.1)
				(type default)
			)
			(layer "F.Fab")
		)
		(fp_line
			(start -0.12065 -0.2794)
			(end 0.12065 -0.2794)
			(stroke
				(width 0.1)
				(type default)
			)
			(layer "F.Fab")
		)
		(fp_line
			(start -0.12065 0.2794)
			(end -0.12065 0.3048)
			(stroke
				(width 0.1)
				(type default)
			)
			(layer "F.Fab")
		)
		(fp_line
			(start -0.12065 0.3048)
			(end -0.67945 0.3048)
			(stroke
				(width 0.1)
				(type default)
			)
			(layer "F.Fab")
		)
		(fp_line
			(start 0.120396 0.2794)
			(end -0.12065 0.2794)
			(stroke
				(width 0.1)
				(type default)
			)
			(layer "F.Fab")
		)
		(fp_line
			(start 0.120396 0.3048)
			(end 0.120396 0.2794)
			(stroke
				(width 0.1)
				(type default)
			)
			(layer "F.Fab")
		)
		(fp_line
			(start 0.12065 -0.3048)
			(end 0.67945 -0.3048)
			(stroke
				(width 0.1)
				(type default)
			)
			(layer "F.Fab")
		)
		(fp_line
			(start 0.12065 -0.2794)
			(end 0.12065 -0.3048)
			(stroke
				(width 0.1)
				(type default)
			)
			(layer "F.Fab")
		)
		(fp_line
			(start 0.67945 -0.3048)
			(end 0.67945 0.3048)
			(stroke
				(width 0.1)
				(type default)
			)
			(layer "F.Fab")
		)
		(fp_line
			(start 0.67945 0.3048)
			(end 0.120396 0.3048)
			(stroke
				(width 0.1)
				(type default)
			)
			(layer "F.Fab")
		)
		(pad "1" smd circle
			(at -0.40005 0)
			(size 0 0)
			(layers "F.Cu" "F.Mask" "F.Paste")
			(net "VSENSE_VSS_SENSE_A_P0")
		)
		(pad "2" smd circle
			(at 0.40005 0)
			(size 0 0)
			(layers "F.Cu" "F.Mask" "F.Paste")
			(net "GND")
		)
	)
)
